(kicad_pcb
	(version 20260206)
	(generator "pcbnew")
	(generator_version "10.0")
	(general
		(thickness 1.6)
		(legacy_teardrops no)
	)
	(paper "A4")
	(title_block
		(title "04192023_DAF0TMB3IC0_F0TG_MB_C_brd_V02_OCP.brd")
		(comment 1 "Grand Teton / footprints 3228-3236 of 8354")
	)
	(layers
		(0 "F.Cu" signal "TOP")
		(4 "In1.Cu" signal "GND")
		(6 "In2.Cu" signal "IN1")
		(8 "In3.Cu" signal "GND1")
		(10 "In4.Cu" signal "IN2")
		(12 "In5.Cu" signal "GND2")
		(14 "In6.Cu" signal "IN3")
		(16 "In7.Cu" signal "GND3")
		(18 "In8.Cu" signal "VCC")
		(20 "In9.Cu" signal "VCC1")
		(22 "In10.Cu" signal "GND4")
		(24 "In11.Cu" signal "IN4")
		(26 "In12.Cu" signal "GND5")
		(28 "In13.Cu" signal "IN5")
		(30 "In14.Cu" signal "GND6")
		(32 "In15.Cu" signal "IN6")
		(34 "In16.Cu" signal "GND7")
		(2 "B.Cu" signal "BOTTOM")
		(9 "F.Adhes" user "F.Adhesive")
		(11 "B.Adhes" user "B.Adhesive")
		(13 "F.Paste" user "Package Geometry/Pastemask Top")
		(15 "B.Paste" user "Package Geometry/Pastemask Bottom")
		(5 "F.SilkS" user "Ref Des/Silkscreen Top")
		(7 "B.SilkS" user "Ref Des/Silkscreen Bottom")
		(1 "F.Mask" user "Board Geometry/Soldermask Top")
		(3 "B.Mask" user "Board Geometry/Soldermask Bottom")
		(17 "Dwgs.User" user "User.Drawings")
		(19 "Cmts.User" user "User.Comments")
		(21 "Eco1.User" user "User.Eco1")
		(23 "Eco2.User" user "User.Eco2")
		(25 "Edge.Cuts" user "Board Geometry/Outline")
		(27 "Margin" user)
		(31 "F.CrtYd" user "Package Geometry/Place Bound Top")
		(29 "B.CrtYd" user "Package Geometry/Place Bound Bottom")
		(35 "F.Fab" user "Ref Des/Assembly Top")
		(33 "B.Fab" user "Ref Des/Assembly Bottom")
	)
	(footprint ""
		(layer "F.Cu")
		(at 80.173322 -176.40935)
		(property "Reference" "PC260_1"
			(at 0 0 0)
			(layer "F.SilkS")
			(hide yes)
			(effects
				(font
					(size 1.27 1.27)
				)
			)
		)
		(property "Value" ""
			(at 0 0 0)
			(layer "F.Fab")
			(effects
				(font
					(size 1.27 1.27)
				)
			)
		)
		(duplicate_pad_numbers_are_jumpers no)
		(fp_line
			(start -0.7874 -0.4064)
			(end 0.7874 -0.4064)
			(stroke
				(width 0.1524)
				(type default)
			)
			(layer "F.SilkS")
		)
		(fp_line
			(start -0.7874 0.4064)
			(end -0.7874 -0.4064)
			(stroke
				(width 0.1524)
				(type default)
			)
			(layer "F.SilkS")
		)
		(fp_line
			(start 0.7874 -0.4064)
			(end 0.7874 0.4064)
			(stroke
				(width 0.1524)
				(type default)
			)
			(layer "F.SilkS")
		)
		(fp_line
			(start 0.7874 0.4064)
			(end -0.7874 0.4064)
			(stroke
				(width 0.1524)
				(type default)
			)
			(layer "F.SilkS")
		)
		(fp_line
			(start -0.67945 -0.305054)
			(end -0.12065 -0.305054)
			(stroke
				(width 0.1)
				(type default)
			)
			(layer "F.Fab")
		)
		(fp_line
			(start -0.67945 0.3048)
			(end -0.67945 -0.305054)
			(stroke
				(width 0.1)
				(type default)
			)
			(layer "F.Fab")
		)
		(fp_line
			(start -0.12065 -0.305054)
			(end -0.12065 -0.2794)
			(stroke
				(width 0.1)
				(type default)
			)
			(layer "F.Fab")
		)
		(fp_line
			(start -0.12065 -0.2794)
			(end 0.12065 -0.2794)
			(stroke
				(width 0.1)
				(type default)
			)
			(layer "F.Fab")
		)
		(fp_line
			(start -0.12065 0.2794)
			(end -0.12065 0.3048)
			(stroke
				(width 0.1)
				(type default)
			)
			(layer "F.Fab")
		)
		(fp_line
			(start -0.12065 0.3048)
			(end -0.67945 0.3048)
			(stroke
				(width 0.1)
				(type default)
			)
			(layer "F.Fab")
		)
		(fp_line
			(start 0.120396 0.2794)
			(end -0.12065 0.2794)
			(stroke
				(width 0.1)
				(type default)
			)
			(layer "F.Fab")
		)
		(fp_line
			(start 0.120396 0.3048)
			(end 0.120396 0.2794)
			(stroke
				(width 0.1)
				(type default)
			)
			(layer "F.Fab")
		)
		(fp_line
			(start 0.12065 -0.3048)
			(end 0.67945 -0.3048)
			(stroke
				(width 0.1)
				(type default)
			)
			(layer "F.Fab")
		)
		(fp_line
			(start 0.12065 -0.2794)
			(end 0.12065 -0.3048)
			(stroke
				(width 0.1)
				(type default)
			)
			(layer "F.Fab")
		)
		(fp_line
			(start 0.67945 -0.3048)
			(end 0.67945 0.3048)
			(stroke
				(width 0.1)
				(type default)
			)
			(layer "F.Fab")
		)
		(fp_line
			(start 0.67945 0.3048)
			(end 0.120396 0.3048)
			(stroke
				(width 0.1)
				(type default)
			)
			(layer "F.Fab")
		)
		(pad "1" smd circle
			(at -0.40005 0)
			(size 0 0)
			(layers "F.Cu" "F.Mask" "F.Paste")
			(net "SW_P12V_AUX_PVDDCR_CPU0_P1_FLT")
		)
		(pad "2" smd circle
			(at 0.40005 0)
			(size 0 0)
			(layers "F.Cu" "F.Mask" "F.Paste")
			(net "GND")
		)
	)
	(footprint ""
		(layer "F.Cu")
		(at 380.058422 -416.899344 -90)
		(property "Reference" "C6572"
			(at 0 0 270)
			(layer "F.SilkS")
			(hide yes)
			(effects
				(font
					(size 1.27 1.27)
				)
			)
		)
		(property "Value" ""
			(at 0 0 270)
			(layer "F.Fab")
			(effects
				(font
					(size 1.27 1.27)
				)
			)
		)
		(duplicate_pad_numbers_are_jumpers no)
		(fp_line
			(start -0.299974 0.150114)
			(end -0.299974 -0.150114)
			(stroke
				(width 0.1)
				(type default)
			)
			(layer "F.Fab")
		)
		(fp_line
			(start 0.299974 0.150114)
			(end -0.299974 0.150114)
			(stroke
				(width 0.1)
				(type default)
			)
			(layer "F.Fab")
		)
		(fp_line
			(start -0.299974 -0.150114)
			(end 0.299974 -0.150114)
			(stroke
				(width 0.1)
				(type default)
			)
			(layer "F.Fab")
		)
		(fp_line
			(start 0.299974 -0.150114)
			(end 0.299974 0.150114)
			(stroke
				(width 0.1)
				(type default)
			)
			(layer "F.Fab")
		)
		(pad "1" smd rect
			(at -0.2667 0 270)
			(size 0.3048 0.381)
			(layers "F.Cu" "F.Mask" "F.Paste")
			(net "P5E_CPU0_P2_TX_BUF_C_DN<3>")
		)
		(pad "2" smd rect
			(at 0.2667 0 270)
			(size 0.3048 0.381)
			(layers "F.Cu" "F.Mask" "F.Paste")
			(net "P5E_CPU0_P2_TX_BUF_DN<3>")
		)
	)
	(footprint ""
		(layer "F.Cu")
		(at 372.896892 -381.41783 -90)
		(property "Reference" "C891"
			(at 0 0 270)
			(layer "F.SilkS")
			(hide yes)
			(effects
				(font
					(size 1.27 1.27)
				)
			)
		)
		(property "Value" ""
			(at 0 0 270)
			(layer "F.Fab")
			(effects
				(font
					(size 1.27 1.27)
				)
			)
		)
		(duplicate_pad_numbers_are_jumpers no)
		(fp_line
			(start -0.299974 0.150114)
			(end -0.299974 -0.150114)
			(stroke
				(width 0.1)
				(type default)
			)
			(layer "F.Fab")
		)
		(fp_line
			(start 0.299974 0.150114)
			(end -0.299974 0.150114)
			(stroke
				(width 0.1)
				(type default)
			)
			(layer "F.Fab")
		)
		(fp_line
			(start -0.299974 -0.150114)
			(end 0.299974 -0.150114)
			(stroke
				(width 0.1)
				(type default)
			)
			(layer "F.Fab")
		)
		(fp_line
			(start 0.299974 -0.150114)
			(end 0.299974 0.150114)
			(stroke
				(width 0.1)
				(type default)
			)
			(layer "F.Fab")
		)
		(pad "1" smd rect
			(at -0.2667 0 270)
			(size 0.3048 0.381)
			(layers "F.Cu" "F.Mask" "F.Paste")
			(net "P5E_CPU0_P3_TX_C_DP<5>")
		)
		(pad "2" smd rect
			(at 0.2667 0 270)
			(size 0.3048 0.381)
			(layers "F.Cu" "F.Mask" "F.Paste")
			(net "P5E_CPU0_P3_TX_DP<5>")
		)
	)
	(footprint ""
		(layer "F.Cu")
		(at 225.228912 -277.572978 180)
		(property "Reference" "PC6801"
			(at 3.359912 4.213352 0)
			(unlocked yes)
			(layer "F.SilkS")
			(effects
				(font
					(size 0.7874 0.5842)
					(thickness 0.1524)
				)
				(justify left)
			)
		)
		(property "Value" ""
			(at 0 0 180)
			(layer "F.Fab")
			(effects
				(font
					(size 1.27 1.27)
				)
			)
		)
		(duplicate_pad_numbers_are_jumpers no)
		(fp_line
			(start 3.400044 3.400044)
			(end -2.146046 3.400044)
			(stroke
				(width 0.1524)
				(type default)
			)
			(layer "F.SilkS")
		)
		(fp_line
			(start 3.400044 0.9398)
			(end 3.400044 3.400044)
			(stroke
				(width 0.1524)
				(type default)
			)
			(layer "F.SilkS")
		)
		(fp_line
			(start 3.400044 -0.9398)
			(end 3.400044 -3.400044)
			(stroke
				(width 0.1524)
				(type default)
			)
			(layer "F.SilkS")
		)
		(fp_line
			(start 3.400044 -3.400044)
			(end -2.146046 -3.400044)
			(stroke
				(width 0.1524)
				(type default)
			)
			(layer "F.SilkS")
		)
		(fp_line
			(start -2.146046 3.400044)
			(end -3.400044 2.146046)
			(stroke
				(width 0.1524)
				(type default)
			)
			(layer "F.SilkS")
		)
		(fp_line
			(start -2.146046 -3.400044)
			(end -3.400044 -2.146046)
			(stroke
				(width 0.1524)
				(type default)
			)
			(layer "F.SilkS")
		)
		(fp_line
			(start -3.400044 2.146046)
			(end -3.400044 0.9398)
			(stroke
				(width 0.1524)
				(type default)
			)
			(layer "F.SilkS")
		)
		(fp_line
			(start -3.400044 -2.146046)
			(end -3.400044 -0.9398)
			(stroke
				(width 0.1524)
				(type default)
			)
			(layer "F.SilkS")
		)
		(fp_line
			(start 3.400044 3.400044)
			(end 3.400044 -3.400044)
			(stroke
				(width 0.1)
				(type default)
			)
			(layer "F.Fab")
		)
		(fp_line
			(start 3.400044 -3.400044)
			(end -3.400044 -3.400044)
			(stroke
				(width 0.1)
				(type default)
			)
			(layer "F.Fab")
		)
		(fp_line
			(start -3.400044 3.400044)
			(end 3.400044 3.400044)
			(stroke
				(width 0.1)
				(type default)
			)
			(layer "F.Fab")
		)
		(fp_line
			(start -3.400044 -3.400044)
			(end -3.400044 3.400044)
			(stroke
				(width 0.1)
				(type default)
			)
			(layer "F.Fab")
		)
		(pad "1" smd rect
			(at -2.70002 0 90)
			(size 1.6002 3.5052)
			(layers "F.Cu" "F.Mask" "F.Paste")
			(net "SW_P12V_AUX_P1V8_RETIMER_CPU1_FLT")
		)
		(pad "2" smd rect
			(at 2.70002 0 90)
			(size 1.6002 3.5052)
			(layers "F.Cu" "F.Mask" "F.Paste")
			(net "GND")
		)
	)
	(footprint ""
		(layer "F.Cu")
		(at 331.517498 -144.086834 90)
		(property "Reference" "PC209"
			(at 0 0 90)
			(layer "F.SilkS")
			(hide yes)
			(effects
				(font
					(size 1.27 1.27)
				)
			)
		)
		(property "Value" ""
			(at 0 0 90)
			(layer "F.Fab")
			(effects
				(font
					(size 1.27 1.27)
				)
			)
		)
		(duplicate_pad_numbers_are_jumpers no)
		(fp_line
			(start 0.7874 -0.4064)
			(end 0.7874 0.4064)
			(stroke
				(width 0.1524)
				(type default)
			)
			(layer "F.SilkS")
		)
		(fp_line
			(start -0.7874 -0.4064)
			(end 0.7874 -0.4064)
			(stroke
				(width 0.1524)
				(type default)
			)
			(layer "F.SilkS")
		)
		(fp_line
			(start 0.7874 0.4064)
			(end -0.7874 0.4064)
			(stroke
				(width 0.1524)
				(type default)
			)
			(layer "F.SilkS")
		)
		(fp_line
			(start -0.7874 0.4064)
			(end -0.7874 -0.4064)
			(stroke
				(width 0.1524)
				(type default)
			)
			(layer "F.SilkS")
		)
		(fp_line
			(start -0.12065 -0.305054)
			(end -0.12065 -0.2794)
			(stroke
				(width 0.1)
				(type default)
			)
			(layer "F.Fab")
		)
		(fp_line
			(start -0.67945 -0.305054)
			(end -0.12065 -0.305054)
			(stroke
				(width 0.1)
				(type default)
			)
			(layer "F.Fab")
		)
		(fp_line
			(start 0.67945 -0.3048)
			(end 0.67945 0.3048)
			(stroke
				(width 0.1)
				(type default)
			)
			(layer "F.Fab")
		)
		(fp_line
			(start 0.12065 -0.3048)
			(end 0.67945 -0.3048)
			(stroke
				(width 0.1)
				(type default)
			)
			(layer "F.Fab")
		)
		(fp_line
			(start 0.12065 -0.2794)
			(end 0.12065 -0.3048)
			(stroke
				(width 0.1)
				(type default)
			)
			(layer "F.Fab")
		)
		(fp_line
			(start -0.12065 -0.2794)
			(end 0.12065 -0.2794)
			(stroke
				(width 0.1)
				(type default)
			)
			(layer "F.Fab")
		)
		(fp_line
			(start 0.120396 0.2794)
			(end -0.12065 0.2794)
			(stroke
				(width 0.1)
				(type default)
			)
			(layer "F.Fab")
		)
		(fp_line
			(start -0.12065 0.2794)
			(end -0.12065 0.3048)
			(stroke
				(width 0.1)
				(type default)
			)
			(layer "F.Fab")
		)
		(fp_line
			(start 0.67945 0.3048)
			(end 0.120396 0.3048)
			(stroke
				(width 0.1)
				(type default)
			)
			(layer "F.Fab")
		)
		(fp_line
			(start 0.120396 0.3048)
			(end 0.120396 0.2794)
			(stroke
				(width 0.1)
				(type default)
			)
			(layer "F.Fab")
		)
		(fp_line
			(start -0.12065 0.3048)
			(end -0.67945 0.3048)
			(stroke
				(width 0.1)
				(type default)
			)
			(layer "F.Fab")
		)
		(fp_line
			(start -0.67945 0.3048)
			(end -0.67945 -0.305054)
			(stroke
				(width 0.1)
				(type default)
			)
			(layer "F.Fab")
		)
		(pad "1" smd circle
			(at -0.40005 0 90)
			(size 0 0)
			(layers "F.Cu" "F.Mask" "F.Paste")
			(net "SW_PVDD18_S5_P0_BST_R")
		)
		(pad "2" smd circle
			(at 0.40005 0 90)
			(size 0 0)
			(layers "F.Cu" "F.Mask" "F.Paste")
			(net "SW_PVDD18_S5_P0_SW")
		)
	)
	(footprint ""
		(layer "F.Cu")
		(at 408.541982 -416.899344 -90)
		(property "Reference" "C6589"
			(at 0 0 270)
			(layer "F.SilkS")
			(hide yes)
			(effects
				(font
					(size 1.27 1.27)
				)
			)
		)
		(property "Value" ""
			(at 0 0 270)
			(layer "F.Fab")
			(effects
				(font
					(size 1.27 1.27)
				)
			)
		)
		(duplicate_pad_numbers_are_jumpers no)
		(fp_line
			(start -0.299974 0.150114)
			(end -0.299974 -0.150114)
			(stroke
				(width 0.1)
				(type default)
			)
			(layer "F.Fab")
		)
		(fp_line
			(start 0.299974 0.150114)
			(end -0.299974 0.150114)
			(stroke
				(width 0.1)
				(type default)
			)
			(layer "F.Fab")
		)
		(fp_line
			(start -0.299974 -0.150114)
			(end 0.299974 -0.150114)
			(stroke
				(width 0.1)
				(type default)
			)
			(layer "F.Fab")
		)
		(fp_line
			(start 0.299974 -0.150114)
			(end 0.299974 0.150114)
			(stroke
				(width 0.1)
				(type default)
			)
			(layer "F.Fab")
		)
		(pad "1" smd rect
			(at -0.2667 0 270)
			(size 0.3048 0.381)
			(layers "F.Cu" "F.Mask" "F.Paste")
			(net "P5E_CPU0_P2_TX_BUF_C_DP<12>")
		)
		(pad "2" smd rect
			(at 0.2667 0 270)
			(size 0.3048 0.381)
			(layers "F.Cu" "F.Mask" "F.Paste")
			(net "P5E_CPU0_P2_TX_BUF_DP<12>")
		)
	)
	(footprint ""
		(layer "F.Cu")
		(at 69.741034 -379.471428)
		(property "Reference" "C807"
			(at 0 0 0)
			(layer "F.SilkS")
			(hide yes)
			(effects
				(font
					(size 1.27 1.27)
				)
			)
		)
		(property "Value" ""
			(at 0 0 0)
			(layer "F.Fab")
			(effects
				(font
					(size 1.27 1.27)
				)
			)
		)
		(duplicate_pad_numbers_are_jumpers no)
		(fp_line
			(start -0.299974 -0.150114)
			(end 0.299974 -0.150114)
			(stroke
				(width 0.1)
				(type default)
			)
			(layer "F.Fab")
		)
		(fp_line
			(start -0.299974 0.150114)
			(end -0.299974 -0.150114)
			(stroke
				(width 0.1)
				(type default)
			)
			(layer "F.Fab")
		)
		(fp_line
			(start 0.299974 -0.150114)
			(end 0.299974 0.150114)
			(stroke
				(width 0.1)
				(type default)
			)
			(layer "F.Fab")
		)
		(fp_line
			(start 0.299974 0.150114)
			(end -0.299974 0.150114)
			(stroke
				(width 0.1)
				(type default)
			)
			(layer "F.Fab")
		)
		(pad "1" smd rect
			(at -0.2667 0)
			(size 0.3048 0.381)
			(layers "F.Cu" "F.Mask" "F.Paste")
			(net "P5E_CPU1_P0_TX_C_DP<15>")
		)
		(pad "2" smd rect
			(at 0.2667 0)
			(size 0.3048 0.381)
			(layers "F.Cu" "F.Mask" "F.Paste")
			(net "P5E_CPU1_P0_TX_DP<15>")
		)
	)
	(footprint ""
		(layer "F.Cu")
		(at 233.2228 -285.2928)
		(property "Reference" "PC6522"
			(at 0 0 0)
			(layer "F.SilkS")
			(hide yes)
			(effects
				(font
					(size 1.27 1.27)
				)
			)
		)
		(property "Value" ""
			(at 0 0 0)
			(layer "F.Fab")
			(effects
				(font
					(size 1.27 1.27)
				)
			)
		)
		(duplicate_pad_numbers_are_jumpers no)
		(fp_line
			(start -1.524 -0.762)
			(end 1.524 -0.762)
			(stroke
				(width 0.1524)
				(type default)
			)
			(layer "F.SilkS")
		)
		(fp_line
			(start -1.524 0.762)
			(end -1.524 -0.762)
			(stroke
				(width 0.1524)
				(type default)
			)
			(layer "F.SilkS")
		)
		(fp_line
			(start 1.524 -0.762)
			(end 1.524 0.762)
			(stroke
				(width 0.1524)
				(type default)
			)
			(layer "F.SilkS")
		)
		(fp_line
			(start 1.524 0.762)
			(end -1.524 0.762)
			(stroke
				(width 0.1524)
				(type default)
			)
			(layer "F.SilkS")
		)
		(fp_line
			(start -1.1049 -0.724916)
			(end -1.1049 0.724916)
			(stroke
				(width 0.1)
				(type default)
			)
			(layer "F.Fab")
		)
		(fp_line
			(start -1.1049 0.724916)
			(end 1.1049 0.724916)
			(stroke
				(width 0.1)
				(type default)
			)
			(layer "F.Fab")
		)
		(fp_line
			(start 1.1049 -0.724916)
			(end -1.1049 -0.724916)
			(stroke
				(width 0.1)
				(type default)
			)
			(layer "F.Fab")
		)
		(fp_line
			(start 1.1049 0.724916)
			(end 1.1049 -0.724916)
			(stroke
				(width 0.1)
				(type default)
			)
			(layer "F.Fab")
		)
		(pad "1" smd rect
			(at -0.889 0 180)
			(size 1.016 1.27)
			(layers "F.Cu" "F.Mask" "F.Paste")
			(net "SW_P12V_AUX_P1V8_RETIMER_CPU1_FLT")
		)
		(pad "2" smd rect
			(at 0.889 0 180)
			(size 1.016 1.27)
			(layers "F.Cu" "F.Mask" "F.Paste")
			(net "GND")
		)
	)
	(footprint ""
		(layer "F.Cu")
		(at 396.258796 -410.144468 90)
		(property "Reference" "C7002"
			(at 0 0 90)
			(layer "F.SilkS")
			(hide yes)
			(effects
				(font
					(size 1.27 1.27)
				)
			)
		)
		(property "Value" ""
			(at 0 0 90)
			(layer "F.Fab")
			(effects
				(font
					(size 1.27 1.27)
				)
			)
		)
		(duplicate_pad_numbers_are_jumpers no)
		(fp_line
			(start 1.524 -0.762)
			(end 1.524 0.762)
			(stroke
				(width 0.1524)
				(type default)
			)
			(layer "F.SilkS")
		)
		(fp_line
			(start -1.524 -0.762)
			(end 1.524 -0.762)
			(stroke
				(width 0.1524)
				(type default)
			)
			(layer "F.SilkS")
		)
		(fp_line
			(start 1.524 0.762)
			(end -1.524 0.762)
			(stroke
				(width 0.1524)
				(type default)
			)
			(layer "F.SilkS")
		)
		(fp_line
			(start -1.524 0.762)
			(end -1.524 -0.762)
			(stroke
				(width 0.1524)
				(type default)
			)
			(layer "F.SilkS")
		)
		(fp_line
			(start 1.1049 -0.724916)
			(end -1.1049 -0.724916)
			(stroke
				(width 0.1)
				(type default)
			)
			(layer "F.Fab")
		)
		(fp_line
			(start -1.1049 -0.724916)
			(end -1.1049 0.724916)
			(stroke
				(width 0.1)
				(type default)
			)
			(layer "F.Fab")
		)
		(fp_line
			(start 1.1049 0.724916)
			(end 1.1049 -0.724916)
			(stroke
				(width 0.1)
				(type default)
			)
			(layer "F.Fab")
		)
		(fp_line
			(start -1.1049 0.724916)
			(end 1.1049 0.724916)
			(stroke
				(width 0.1)
				(type default)
			)
			(layer "F.Fab")
		)
		(pad "1" smd rect
			(at -0.889 0 270)
			(size 1.016 1.27)
			(layers "F.Cu" "F.Mask" "F.Paste")
			(net "P0V9_CPU0_RT_2D")
		)
		(pad "2" smd rect
			(at 0.889 0 270)
			(size 1.016 1.27)
			(layers "F.Cu" "F.Mask" "F.Paste")
			(net "GND")
		)
	)
)
